# T6G (Grand Teton) — schematic netlist excerpt (pin names and nets, part order shuffled) for the footprints in the layout excerpt that follows; sources: Cadence DE-HDL packaged netlist, KiCad conversion of 04192023_DAF0TMB3IC0_F0TG_MB_C_brd_V02_OCP.brd

C3905  Q_CAP  22UF 4V 20% X6S  pkg C0402  page 72 : A = PVDD11_S3_P1 ; B = GND
R3498  Q_RES  54.9K 1% CHIP  pkg 0402LF  page 126 : A = P3V3_AUX ; B = GPU_FPGA_THERM_OVERT_N
C614  Q_CAP  0.1UF 10V 10% X7S  pkg C0201  page 290 : A = P0V9_CPU0_RT1_2A ; B = GND

(kicad_pcb
	(version 20260206)
	(generator "pcbnew")
	(generator_version "10.0")
	(general
		(thickness 1.6)
		(legacy_teardrops no)
	)
	(paper "A4")
	(title_block
		(title "04192023_DAF0TMB3IC0_F0TG_MB_C_brd_V02_OCP.brd")
		(comment 1 "Grand Teton / footprints 5874-5876 of 8354")
	)
	(layers
		(0 "F.Cu" signal "TOP")
		(4 "In1.Cu" signal "GND")
		(6 "In2.Cu" signal "IN1")
		(8 "In3.Cu" signal "GND1")
		(10 "In4.Cu" signal "IN2")
		(12 "In5.Cu" signal "GND2")
		(14 "In6.Cu" signal "IN3")
		(16 "In7.Cu" signal "GND3")
		(18 "In8.Cu" signal "VCC")
		(20 "In9.Cu" signal "VCC1")
		(22 "In10.Cu" signal "GND4")
		(24 "In11.Cu" signal "IN4")
		(26 "In12.Cu" signal "GND5")
		(28 "In13.Cu" signal "IN5")
		(30 "In14.Cu" signal "GND6")
		(32 "In15.Cu" signal "IN6")
		(34 "In16.Cu" signal "GND7")
		(2 "B.Cu" signal "BOTTOM")
		(9 "F.Adhes" user "F.Adhesive")
		(11 "B.Adhes" user "B.Adhesive")
		(13 "F.Paste" user "Package Geometry/Pastemask Top")
		(15 "B.Paste" user "Package Geometry/Pastemask Bottom")
		(5 "F.SilkS" user "Ref Des/Silkscreen Top")
		(7 "B.SilkS" user "Ref Des/Silkscreen Bottom")
		(1 "F.Mask" user "Board Geometry/Soldermask Top")
		(3 "B.Mask" user "Board Geometry/Soldermask Bottom")
		(17 "Dwgs.User" user "User.Drawings")
		(19 "Cmts.User" user "User.Comments")
		(21 "Eco1.User" user "User.Eco1")
		(23 "Eco2.User" user "User.Eco2")
		(25 "Edge.Cuts" user "Board Geometry/Outline")
		(27 "Margin" user)
		(31 "F.CrtYd" user "Package Geometry/Place Bound Top")
		(29 "B.CrtYd" user "Package Geometry/Place Bound Bottom")
		(35 "F.Fab" user "Ref Des/Assembly Top")
		(33 "B.Fab" user "Ref Des/Assembly Bottom")
	)
	(footprint ""
		(layer "B.Cu")
		(at 51.766978 -433.682902 90)
		(property "Reference" "R3498"
			(at 0 0 90)
			(layer "B.SilkS")
			(hide yes)
			(effects
				(font
					(size 1.27 1.27)
				)
				(justify mirror)
			)
		)
		(property "Value" ""
			(at 0 0 90)
			(layer "B.Fab")
			(effects
				(font
					(size 1.27 1.27)
				)
				(justify mirror)
			)
		)
		(duplicate_pad_numbers_are_jumpers no)
		(fp_line
			(start 0.7874 -0.4064)
			(end -0.7874 -0.4064)
			(stroke
				(width 0.1524)
				(type default)
			)
			(layer "B.SilkS")
		)
		(fp_line
			(start -0.7874 -0.4064)
			(end -0.7874 0.4064)
			(stroke
				(width 0.1524)
				(type default)
			)
			(layer "B.SilkS")
		)
		(fp_line
			(start 0.7874 0.4064)
			(end 0.7874 -0.4064)
			(stroke
				(width 0.1524)
				(type default)
			)
			(layer "B.SilkS")
		)
		(fp_line
			(start -0.7874 0.4064)
			(end 0.7874 0.4064)
			(stroke
				(width 0.1524)
				(type default)
			)
			(layer "B.SilkS")
		)
		(fp_line
			(start 0.67945 -0.305054)
			(end 0.12065 -0.305054)
			(stroke
				(width 0.1)
				(type default)
			)
			(layer "B.Fab")
		)
		(fp_line
			(start 0.12065 -0.305054)
			(end 0.12065 -0.2794)
			(stroke
				(width 0.1)
				(type default)
			)
			(layer "B.Fab")
		)
		(fp_line
			(start -0.12065 -0.3048)
			(end -0.67945 -0.3048)
			(stroke
				(width 0.1)
				(type default)
			)
			(layer "B.Fab")
		)
		(fp_line
			(start -0.67945 -0.3048)
			(end -0.67945 0.3048)
			(stroke
				(width 0.1)
				(type default)
			)
			(layer "B.Fab")
		)
		(fp_line
			(start 0.12065 -0.2794)
			(end -0.12065 -0.2794)
			(stroke
				(width 0.1)
				(type default)
			)
			(layer "B.Fab")
		)
		(fp_line
			(start -0.12065 -0.2794)
			(end -0.12065 -0.3048)
			(stroke
				(width 0.1)
				(type default)
			)
			(layer "B.Fab")
		)
		(fp_line
			(start 0.12065 0.2794)
			(end 0.12065 0.3048)
			(stroke
				(width 0.1)
				(type default)
			)
			(layer "B.Fab")
		)
		(fp_line
			(start -0.120396 0.2794)
			(end 0.12065 0.2794)
			(stroke
				(width 0.1)
				(type default)
			)
			(layer "B.Fab")
		)
		(fp_line
			(start 0.67945 0.3048)
			(end 0.67945 -0.305054)
			(stroke
				(width 0.1)
				(type default)
			)
			(layer "B.Fab")
		)
		(fp_line
			(start 0.12065 0.3048)
			(end 0.67945 0.3048)
			(stroke
				(width 0.1)
				(type default)
			)
			(layer "B.Fab")
		)
		(fp_line
			(start -0.120396 0.3048)
			(end -0.120396 0.2794)
			(stroke
				(width 0.1)
				(type default)
			)
			(layer "B.Fab")
		)
		(fp_line
			(start -0.67945 0.3048)
			(end -0.120396 0.3048)
			(stroke
				(width 0.1)
				(type default)
			)
			(layer "B.Fab")
		)
		(pad "1" smd circle
			(at 0.40005 0 270)
			(size 0 0)
			(layers "B.Cu" "B.Mask" "B.Paste")
			(net "P3V3_AUX")
		)
		(pad "2" smd circle
			(at -0.40005 0 270)
			(size 0 0)
			(layers "B.Cu" "B.Mask" "B.Paste")
			(net "GPU_FPGA_THERM_OVERT_N")
		)
	)
	(footprint ""
		(layer "B.Cu")
		(at 112.054386 -264.862564)
		(property "Reference" "C3905"
			(at 0 0 0)
			(layer "B.SilkS")
			(hide yes)
			(effects
				(font
					(size 1.27 1.27)
				)
				(justify mirror)
			)
		)
		(property "Value" ""
			(at 0 0 0)
			(layer "B.Fab")
			(effects
				(font
					(size 1.27 1.27)
				)
				(justify mirror)
			)
		)
		(duplicate_pad_numbers_are_jumpers no)
		(fp_line
			(start -0.7874 -0.4064)
			(end -0.7874 0.4064)
			(stroke
				(width 0.1524)
				(type default)
			)
			(layer "B.SilkS")
		)
		(fp_line
			(start -0.7874 0.4064)
			(end 0.7874 0.4064)
			(stroke
				(width 0.1524)
				(type default)
			)
			(layer "B.SilkS")
		)
		(fp_line
			(start 0.7874 -0.4064)
			(end -0.7874 -0.4064)
			(stroke
				(width 0.1524)
				(type default)
			)
			(layer "B.SilkS")
		)
		(fp_line
			(start 0.7874 0.4064)
			(end 0.7874 -0.4064)
			(stroke
				(width 0.1524)
				(type default)
			)
			(layer "B.SilkS")
		)
		(fp_line
			(start -0.67945 -0.3048)
			(end -0.67945 0.3048)
			(stroke
				(width 0.1)
				(type default)
			)
			(layer "B.Fab")
		)
		(fp_line
			(start -0.67945 0.3048)
			(end -0.120396 0.3048)
			(stroke
				(width 0.1)
				(type default)
			)
			(layer "B.Fab")
		)
		(fp_line
			(start -0.12065 -0.3048)
			(end -0.67945 -0.3048)
			(stroke
				(width 0.1)
				(type default)
			)
			(layer "B.Fab")
		)
		(fp_line
			(start -0.12065 -0.2794)
			(end -0.12065 -0.3048)
			(stroke
				(width 0.1)
				(type default)
			)
			(layer "B.Fab")
		)
		(fp_line
			(start -0.120396 0.2794)
			(end 0.12065 0.2794)
			(stroke
				(width 0.1)
				(type default)
			)
			(layer "B.Fab")
		)
		(fp_line
			(start -0.120396 0.3048)
			(end -0.120396 0.2794)
			(stroke
				(width 0.1)
				(type default)
			)
			(layer "B.Fab")
		)
		(fp_line
			(start 0.12065 -0.305054)
			(end 0.12065 -0.2794)
			(stroke
				(width 0.1)
				(type default)
			)
			(layer "B.Fab")
		)
		(fp_line
			(start 0.12065 -0.2794)
			(end -0.12065 -0.2794)
			(stroke
				(width 0.1)
				(type default)
			)
			(layer "B.Fab")
		)
		(fp_line
			(start 0.12065 0.2794)
			(end 0.12065 0.3048)
			(stroke
				(width 0.1)
				(type default)
			)
			(layer "B.Fab")
		)
		(fp_line
			(start 0.12065 0.3048)
			(end 0.67945 0.3048)
			(stroke
				(width 0.1)
				(type default)
			)
			(layer "B.Fab")
		)
		(fp_line
			(start 0.67945 -0.305054)
			(end 0.12065 -0.305054)
			(stroke
				(width 0.1)
				(type default)
			)
			(layer "B.Fab")
		)
		(fp_line
			(start 0.67945 0.3048)
			(end 0.67945 -0.305054)
			(stroke
				(width 0.1)
				(type default)
			)
			(layer "B.Fab")
		)
		(pad "1" smd circle
			(at 0.40005 0 180)
			(size 0 0)
			(layers "B.Cu" "B.Mask" "B.Paste")
			(net "PVDD11_S3_P1")
		)
		(pad "2" smd circle
			(at -0.40005 0 180)
			(size 0 0)
			(layers "B.Cu" "B.Mask" "B.Paste")
			(net "GND")
		)
	)
	(footprint ""
		(layer "B.Cu")
		(at 354.046028 -396.393162 -90)
		(property "Reference" "C614"
			(at 0 0 90)
			(layer "B.SilkS")
			(hide yes)
			(effects
				(font
					(size 1.27 1.27)
				)
				(justify mirror)
			)
		)
		(property "Value" ""
			(at 0 0 90)
			(layer "B.Fab")
			(effects
				(font
					(size 1.27 1.27)
				)
				(justify mirror)
			)
		)
		(duplicate_pad_numbers_are_jumpers no)
		(fp_line
			(start -0.299974 0.150114)
			(end 0.299974 0.150114)
			(stroke
				(width 0.1)
				(type default)
			)
			(layer "B.Fab")
		)
		(fp_line
			(start 0.299974 0.150114)
			(end 0.299974 -0.150114)
			(stroke
				(width 0.1)
				(type default)
			)
			(layer "B.Fab")
		)
		(fp_line
			(start -0.299974 -0.150114)
			(end -0.299974 0.150114)
			(stroke
				(width 0.1)
				(type default)
			)
			(layer "B.Fab")
		)
		(fp_line
			(start 0.299974 -0.150114)
			(end -0.299974 -0.150114)
			(stroke
				(width 0.1)
				(type default)
			)
			(layer "B.Fab")
		)
		(pad "1" smd rect
			(at 0.2667 0 90)
			(size 0.3048 0.381)
			(layers "B.Cu" "B.Mask" "B.Paste")
			(net "P0V9_CPU0_RT1_2A")
		)
		(pad "2" smd rect
			(at -0.2667 0 90)
			(size 0.3048 0.381)
			(layers "B.Cu" "B.Mask" "B.Paste")
			(net "GND")
		)
	)
)
